(kicad_pcb
	(version 20260206)
	(generator "pcbnew")
	(generator_version "10.0")
	(general
		(thickness 1.6)
		(legacy_teardrops no)
	)
	(paper "A4")
	(title_block
		(title "01162023_DA0F0TEBIF0_F0T_Expander_BD_F_brd_V02_OCP.brd")
		(comment 1 "Grand Teton / footprints 7417-7427 of 9728")
	)
	(layers
		(0 "F.Cu" signal "TOP")
		(4 "In1.Cu" signal "GND")
		(6 "In2.Cu" signal "VCC")
		(8 "In3.Cu" signal "VCC1")
		(10 "In4.Cu" signal "GND1")
		(12 "In5.Cu" signal "IN1")
		(14 "In6.Cu" signal "GND2")
		(16 "In7.Cu" signal "IN2")
		(18 "In8.Cu" signal "GND3")
		(20 "In9.Cu" signal "IN3")
		(22 "In10.Cu" signal "GND4")
		(24 "In11.Cu" signal "IN4")
		(26 "In12.Cu" signal "GND5")
		(28 "In13.Cu" signal "IN5")
		(30 "In14.Cu" signal "GND6")
		(32 "In15.Cu" signal "IN6")
		(34 "In16.Cu" signal "GND7")
		(2 "B.Cu" signal "BOTTOM")
		(9 "F.Adhes" user "F.Adhesive")
		(11 "B.Adhes" user "B.Adhesive")
		(13 "F.Paste" user "Package Geometry/Pastemask Top")
		(15 "B.Paste" user "Package Geometry/Pastemask Bottom")
		(5 "F.SilkS" user "Ref Des/Silkscreen Top")
		(7 "B.SilkS" user "Ref Des/Silkscreen Bottom")
		(1 "F.Mask" user "Board Geometry/Soldermask Top")
		(3 "B.Mask" user "Board Geometry/Soldermask Bottom")
		(17 "Dwgs.User" user "User.Drawings")
		(19 "Cmts.User" user "User.Comments")
		(21 "Eco1.User" user "User.Eco1")
		(23 "Eco2.User" user "User.Eco2")
		(25 "Edge.Cuts" user "Board Geometry/Outline")
		(27 "Margin" user)
		(31 "F.CrtYd" user "Package Geometry/Place Bound Top")
		(29 "B.CrtYd" user "Package Geometry/Place Bound Bottom")
		(35 "F.Fab" user "Ref Des/Assembly Top")
		(33 "B.Fab" user "Ref Des/Assembly Bottom")
	)
	(footprint ""
		(layer "B.Cu")
		(at 294.251126 -305.399948 -90)
		(property "Reference" "C3314"
			(at 0 0 90)
			(layer "B.SilkS")
			(hide yes)
			(effects
				(font
					(size 1.27 1.27)
				)
				(justify mirror)
			)
		)
		(property "Value" ""
			(at 0 0 90)
			(layer "B.Fab")
			(effects
				(font
					(size 1.27 1.27)
				)
				(justify mirror)
			)
		)
		(duplicate_pad_numbers_are_jumpers no)
		(fp_line
			(start -0.299974 0.150114)
			(end 0.299974 0.150114)
			(stroke
				(width 0.1)
				(type default)
			)
			(layer "B.Fab")
		)
		(fp_line
			(start 0.299974 0.150114)
			(end 0.299974 -0.150114)
			(stroke
				(width 0.1)
				(type default)
			)
			(layer "B.Fab")
		)
		(fp_line
			(start -0.299974 -0.150114)
			(end -0.299974 0.150114)
			(stroke
				(width 0.1)
				(type default)
			)
			(layer "B.Fab")
		)
		(fp_line
			(start 0.299974 -0.150114)
			(end -0.299974 -0.150114)
			(stroke
				(width 0.1)
				(type default)
			)
			(layer "B.Fab")
		)
		(pad "1" smd rect
			(at 0.2667 0 90)
			(size 0.3048 0.381)
			(layers "B.Cu" "B.Mask" "B.Paste")
			(net "P1V25_SERDES_VDDPLL_PEX2")
		)
		(pad "2" smd rect
			(at -0.2667 0 90)
			(size 0.3048 0.381)
			(layers "B.Cu" "B.Mask" "B.Paste")
			(net "GND")
		)
	)
	(footprint ""
		(layer "B.Cu")
		(at 405.575008 -293.99992 -90)
		(property "Reference" "C1906"
			(at 0 0 90)
			(layer "B.SilkS")
			(hide yes)
			(effects
				(font
					(size 1.27 1.27)
				)
				(justify mirror)
			)
		)
		(property "Value" ""
			(at 0 0 90)
			(layer "B.Fab")
			(effects
				(font
					(size 1.27 1.27)
				)
				(justify mirror)
			)
		)
		(duplicate_pad_numbers_are_jumpers no)
		(fp_line
			(start -0.299974 0.150114)
			(end 0.299974 0.150114)
			(stroke
				(width 0.1)
				(type default)
			)
			(layer "B.Fab")
		)
		(fp_line
			(start 0.299974 0.150114)
			(end 0.299974 -0.150114)
			(stroke
				(width 0.1)
				(type default)
			)
			(layer "B.Fab")
		)
		(fp_line
			(start -0.299974 -0.150114)
			(end -0.299974 0.150114)
			(stroke
				(width 0.1)
				(type default)
			)
			(layer "B.Fab")
		)
		(fp_line
			(start 0.299974 -0.150114)
			(end -0.299974 -0.150114)
			(stroke
				(width 0.1)
				(type default)
			)
			(layer "B.Fab")
		)
		(pad "1" smd rect
			(at 0.2667 0 90)
			(size 0.3048 0.381)
			(layers "B.Cu" "B.Mask" "B.Paste")
			(net "P0V8_PEX3")
		)
		(pad "2" smd rect
			(at -0.2667 0 90)
			(size 0.3048 0.381)
			(layers "B.Cu" "B.Mask" "B.Paste")
			(net "GND")
		)
	)
	(footprint ""
		(layer "B.Cu")
		(at 100.571554 -308.4576 90)
		(property "Reference" "C4190"
			(at 0 0 90)
			(layer "B.SilkS")
			(hide yes)
			(effects
				(font
					(size 1.27 1.27)
				)
				(justify mirror)
			)
		)
		(property "Value" ""
			(at 0 0 90)
			(layer "B.Fab")
			(effects
				(font
					(size 1.27 1.27)
				)
				(justify mirror)
			)
		)
		(duplicate_pad_numbers_are_jumpers no)
		(fp_line
			(start 0.299974 -0.150114)
			(end -0.299974 -0.150114)
			(stroke
				(width 0.1)
				(type default)
			)
			(layer "B.Fab")
		)
		(fp_line
			(start -0.299974 -0.150114)
			(end -0.299974 0.150114)
			(stroke
				(width 0.1)
				(type default)
			)
			(layer "B.Fab")
		)
		(fp_line
			(start 0.299974 0.150114)
			(end 0.299974 -0.150114)
			(stroke
				(width 0.1)
				(type default)
			)
			(layer "B.Fab")
		)
		(fp_line
			(start -0.299974 0.150114)
			(end 0.299974 0.150114)
			(stroke
				(width 0.1)
				(type default)
			)
			(layer "B.Fab")
		)
		(pad "1" smd rect
			(at 0.2667 0 270)
			(size 0.3048 0.381)
			(layers "B.Cu" "B.Mask" "B.Paste")
			(net "P0V8_PEX0")
		)
		(pad "2" smd rect
			(at -0.2667 0 270)
			(size 0.3048 0.381)
			(layers "B.Cu" "B.Mask" "B.Paste")
			(net "GND")
		)
	)
	(footprint ""
		(layer "B.Cu")
		(at 113.337848 -325.161656 -90)
		(property "Reference" "C4213"
			(at 0 0 90)
			(layer "B.SilkS")
			(hide yes)
			(effects
				(font
					(size 1.27 1.27)
				)
				(justify mirror)
			)
		)
		(property "Value" ""
			(at 0 0 90)
			(layer "B.Fab")
			(effects
				(font
					(size 1.27 1.27)
				)
				(justify mirror)
			)
		)
		(duplicate_pad_numbers_are_jumpers no)
		(fp_line
			(start -1.2954 0.5842)
			(end 1.2954 0.5842)
			(stroke
				(width 0.1524)
				(type default)
			)
			(layer "B.SilkS")
		)
		(fp_line
			(start 1.2954 0.5842)
			(end 1.2954 -0.5842)
			(stroke
				(width 0.1524)
				(type default)
			)
			(layer "B.SilkS")
		)
		(fp_line
			(start -1.2954 -0.5842)
			(end -1.2954 0.5842)
			(stroke
				(width 0.1524)
				(type default)
			)
			(layer "B.SilkS")
		)
		(fp_line
			(start 1.2954 -0.5842)
			(end -1.2954 -0.5842)
			(stroke
				(width 0.1524)
				(type default)
			)
			(layer "B.SilkS")
		)
		(fp_line
			(start -0.8636 0.4572)
			(end 0.8636 0.4572)
			(stroke
				(width 0.1)
				(type default)
			)
			(layer "B.Fab")
		)
		(fp_line
			(start 0.8636 0.4572)
			(end 0.8636 0.4064)
			(stroke
				(width 0.1)
				(type default)
			)
			(layer "B.Fab")
		)
		(fp_line
			(start -1.1938 0.4064)
			(end -0.8636 0.4064)
			(stroke
				(width 0.1)
				(type default)
			)
			(layer "B.Fab")
		)
		(fp_line
			(start -0.8636 0.4064)
			(end -0.8636 0.4572)
			(stroke
				(width 0.1)
				(type default)
			)
			(layer "B.Fab")
		)
		(fp_line
			(start 0.8636 0.4064)
			(end 1.1938 0.4064)
			(stroke
				(width 0.1)
				(type default)
			)
			(layer "B.Fab")
		)
		(fp_line
			(start 1.1938 0.4064)
			(end 1.1938 -0.4064)
			(stroke
				(width 0.1)
				(type default)
			)
			(layer "B.Fab")
		)
		(fp_line
			(start -1.1938 -0.4064)
			(end -1.1938 0.4064)
			(stroke
				(width 0.1)
				(type default)
			)
			(layer "B.Fab")
		)
		(fp_line
			(start -0.8636 -0.4064)
			(end -1.1938 -0.4064)
			(stroke
				(width 0.1)
				(type default)
			)
			(layer "B.Fab")
		)
		(fp_line
			(start 0.8636 -0.4064)
			(end 0.8636 -0.4572)
			(stroke
				(width 0.1)
				(type default)
			)
			(layer "B.Fab")
		)
		(fp_line
			(start 1.1938 -0.4064)
			(end 0.8636 -0.4064)
			(stroke
				(width 0.1)
				(type default)
			)
			(layer "B.Fab")
		)
		(fp_line
			(start -0.8636 -0.4572)
			(end -0.8636 -0.4064)
			(stroke
				(width 0.1)
				(type default)
			)
			(layer "B.Fab")
		)
		(fp_line
			(start 0.8636 -0.4572)
			(end -0.8636 -0.4572)
			(stroke
				(width 0.1)
				(type default)
			)
			(layer "B.Fab")
		)
		(pad "1" smd rect
			(at 0.7366 0 180)
			(size 0.7112 0.8128)
			(layers "B.Cu" "B.Mask" "B.Paste")
			(net "P0V8_SERDES_VDDA_PEX0_C7")
		)
		(pad "2" smd rect
			(at -0.7366 0 180)
			(size 0.7112 0.8128)
			(layers "B.Cu" "B.Mask" "B.Paste")
			(net "GND")
		)
	)
	(footprint ""
		(layer "B.Cu")
		(at 405.520144 -305.399948 -90)
		(property "Reference" "C3487"
			(at 0 0 90)
			(layer "B.SilkS")
			(hide yes)
			(effects
				(font
					(size 1.27 1.27)
				)
				(justify mirror)
			)
		)
		(property "Value" ""
			(at 0 0 90)
			(layer "B.Fab")
			(effects
				(font
					(size 1.27 1.27)
				)
				(justify mirror)
			)
		)
		(duplicate_pad_numbers_are_jumpers no)
		(fp_line
			(start -0.299974 0.150114)
			(end 0.299974 0.150114)
			(stroke
				(width 0.1)
				(type default)
			)
			(layer "B.Fab")
		)
		(fp_line
			(start 0.299974 0.150114)
			(end 0.299974 -0.150114)
			(stroke
				(width 0.1)
				(type default)
			)
			(layer "B.Fab")
		)
		(fp_line
			(start -0.299974 -0.150114)
			(end -0.299974 0.150114)
			(stroke
				(width 0.1)
				(type default)
			)
			(layer "B.Fab")
		)
		(fp_line
			(start 0.299974 -0.150114)
			(end -0.299974 -0.150114)
			(stroke
				(width 0.1)
				(type default)
			)
			(layer "B.Fab")
		)
		(pad "1" smd rect
			(at 0.2667 0 90)
			(size 0.3048 0.381)
			(layers "B.Cu" "B.Mask" "B.Paste")
			(net "P1V25_SERDES_VDDPLL_PEX3")
		)
		(pad "2" smd rect
			(at -0.2667 0 90)
			(size 0.3048 0.381)
			(layers "B.Cu" "B.Mask" "B.Paste")
			(net "GND")
		)
	)
	(footprint ""
		(layer "B.Cu")
		(at 189.049914 -294.94988 180)
		(property "Reference" "C3121"
			(at 0 0 0)
			(layer "B.SilkS")
			(hide yes)
			(effects
				(font
					(size 1.27 1.27)
				)
				(justify mirror)
			)
		)
		(property "Value" ""
			(at 0 0 0)
			(layer "B.Fab")
			(effects
				(font
					(size 1.27 1.27)
				)
				(justify mirror)
			)
		)
		(duplicate_pad_numbers_are_jumpers no)
		(fp_line
			(start 0.299974 0.150114)
			(end 0.299974 -0.150114)
			(stroke
				(width 0.1)
				(type default)
			)
			(layer "B.Fab")
		)
		(fp_line
			(start 0.299974 -0.150114)
			(end -0.299974 -0.150114)
			(stroke
				(width 0.1)
				(type default)
			)
			(layer "B.Fab")
		)
		(fp_line
			(start -0.299974 0.150114)
			(end 0.299974 0.150114)
			(stroke
				(width 0.1)
				(type default)
			)
			(layer "B.Fab")
		)
		(fp_line
			(start -0.299974 -0.150114)
			(end -0.299974 0.150114)
			(stroke
				(width 0.1)
				(type default)
			)
			(layer "B.Fab")
		)
		(pad "1" smd rect
			(at 0.2667 0)
			(size 0.3048 0.381)
			(layers "B.Cu" "B.Mask" "B.Paste")
			(net "P1V25_SERDES_VDDPLL_PEX1")
		)
		(pad "2" smd rect
			(at -0.2667 0)
			(size 0.3048 0.381)
			(layers "B.Cu" "B.Mask" "B.Paste")
			(net "GND")
		)
	)
	(footprint ""
		(layer "B.Cu")
		(at 399.400014 -292.099746 90)
		(property "Reference" "C1954"
			(at 0 0 90)
			(layer "B.SilkS")
			(hide yes)
			(effects
				(font
					(size 1.27 1.27)
				)
				(justify mirror)
			)
		)
		(property "Value" ""
			(at 0 0 90)
			(layer "B.Fab")
			(effects
				(font
					(size 1.27 1.27)
				)
				(justify mirror)
			)
		)
		(duplicate_pad_numbers_are_jumpers no)
		(fp_line
			(start 0.299974 -0.150114)
			(end -0.299974 -0.150114)
			(stroke
				(width 0.1)
				(type default)
			)
			(layer "B.Fab")
		)
		(fp_line
			(start -0.299974 -0.150114)
			(end -0.299974 0.150114)
			(stroke
				(width 0.1)
				(type default)
			)
			(layer "B.Fab")
		)
		(fp_line
			(start 0.299974 0.150114)
			(end 0.299974 -0.150114)
			(stroke
				(width 0.1)
				(type default)
			)
			(layer "B.Fab")
		)
		(fp_line
			(start -0.299974 0.150114)
			(end 0.299974 0.150114)
			(stroke
				(width 0.1)
				(type default)
			)
			(layer "B.Fab")
		)
		(pad "1" smd rect
			(at 0.2667 0 270)
			(size 0.3048 0.381)
			(layers "B.Cu" "B.Mask" "B.Paste")
			(net "P0V8_SERDES_VDDA_PEX3")
		)
		(pad "2" smd rect
			(at -0.2667 0 270)
			(size 0.3048 0.381)
			(layers "B.Cu" "B.Mask" "B.Paste")
			(net "GND")
		)
	)
	(footprint ""
		(layer "B.Cu")
		(at 290.42487 -286.399732 90)
		(property "Reference" "C3307"
			(at 0 0 90)
			(layer "B.SilkS")
			(hide yes)
			(effects
				(font
					(size 1.27 1.27)
				)
				(justify mirror)
			)
		)
		(property "Value" ""
			(at 0 0 90)
			(layer "B.Fab")
			(effects
				(font
					(size 1.27 1.27)
				)
				(justify mirror)
			)
		)
		(duplicate_pad_numbers_are_jumpers no)
		(fp_line
			(start 0.299974 -0.150114)
			(end -0.299974 -0.150114)
			(stroke
				(width 0.1)
				(type default)
			)
			(layer "B.Fab")
		)
		(fp_line
			(start -0.299974 -0.150114)
			(end -0.299974 0.150114)
			(stroke
				(width 0.1)
				(type default)
			)
			(layer "B.Fab")
		)
		(fp_line
			(start 0.299974 0.150114)
			(end 0.299974 -0.150114)
			(stroke
				(width 0.1)
				(type default)
			)
			(layer "B.Fab")
		)
		(fp_line
			(start -0.299974 0.150114)
			(end 0.299974 0.150114)
			(stroke
				(width 0.1)
				(type default)
			)
			(layer "B.Fab")
		)
		(pad "1" smd rect
			(at 0.2667 0 270)
			(size 0.3048 0.381)
			(layers "B.Cu" "B.Mask" "B.Paste")
			(net "P1V25_SERDES_VDDPLL_PEX2")
		)
		(pad "2" smd rect
			(at -0.2667 0 270)
			(size 0.3048 0.381)
			(layers "B.Cu" "B.Mask" "B.Paste")
			(net "GND")
		)
	)
	(footprint ""
		(layer "B.Cu")
		(at 214.454486 -216.270586 180)
		(property "Reference" "R5720"
			(at 0 0 0)
			(layer "B.SilkS")
			(hide yes)
			(effects
				(font
					(size 1.27 1.27)
				)
				(justify mirror)
			)
		)
		(property "Value" ""
			(at 0 0 0)
			(layer "B.Fab")
			(effects
				(font
					(size 1.27 1.27)
				)
				(justify mirror)
			)
		)
		(duplicate_pad_numbers_are_jumpers no)
		(fp_line
			(start 0.7874 0.4064)
			(end 0.7874 -0.4064)
			(stroke
				(width 0.1524)
				(type default)
			)
			(layer "B.SilkS")
		)
		(fp_line
			(start 0.7874 -0.4064)
			(end -0.7874 -0.4064)
			(stroke
				(width 0.1524)
				(type default)
			)
			(layer "B.SilkS")
		)
		(fp_line
			(start -0.7874 0.4064)
			(end 0.7874 0.4064)
			(stroke
				(width 0.1524)
				(type default)
			)
			(layer "B.SilkS")
		)
		(fp_line
			(start -0.7874 -0.4064)
			(end -0.7874 0.4064)
			(stroke
				(width 0.1524)
				(type default)
			)
			(layer "B.SilkS")
		)
		(fp_line
			(start 0.67945 0.3048)
			(end 0.67945 -0.305054)
			(stroke
				(width 0.1)
				(type default)
			)
			(layer "B.Fab")
		)
		(fp_line
			(start 0.67945 -0.305054)
			(end 0.12065 -0.305054)
			(stroke
				(width 0.1)
				(type default)
			)
			(layer "B.Fab")
		)
		(fp_line
			(start 0.12065 0.3048)
			(end 0.67945 0.3048)
			(stroke
				(width 0.1)
				(type default)
			)
			(layer "B.Fab")
		)
		(fp_line
			(start 0.12065 0.2794)
			(end 0.12065 0.3048)
			(stroke
				(width 0.1)
				(type default)
			)
			(layer "B.Fab")
		)
		(fp_line
			(start 0.12065 -0.2794)
			(end -0.12065 -0.2794)
			(stroke
				(width 0.1)
				(type default)
			)
			(layer "B.Fab")
		)
		(fp_line
			(start 0.12065 -0.305054)
			(end 0.12065 -0.2794)
			(stroke
				(width 0.1)
				(type default)
			)
			(layer "B.Fab")
		)
		(fp_line
			(start -0.120396 0.3048)
			(end -0.120396 0.2794)
			(stroke
				(width 0.1)
				(type default)
			)
			(layer "B.Fab")
		)
		(fp_line
			(start -0.120396 0.2794)
			(end 0.12065 0.2794)
			(stroke
				(width 0.1)
				(type default)
			)
			(layer "B.Fab")
		)
		(fp_line
			(start -0.12065 -0.2794)
			(end -0.12065 -0.3048)
			(stroke
				(width 0.1)
				(type default)
			)
			(layer "B.Fab")
		)
		(fp_line
			(start -0.12065 -0.3048)
			(end -0.67945 -0.3048)
			(stroke
				(width 0.1)
				(type default)
			)
			(layer "B.Fab")
		)
		(fp_line
			(start -0.67945 0.3048)
			(end -0.120396 0.3048)
			(stroke
				(width 0.1)
				(type default)
			)
			(layer "B.Fab")
		)
		(fp_line
			(start -0.67945 -0.3048)
			(end -0.67945 0.3048)
			(stroke
				(width 0.1)
				(type default)
			)
			(layer "B.Fab")
		)
		(pad "1" smd circle
			(at 0.40005 0)
			(size 0 0)
			(layers "B.Cu" "B.Mask" "B.Paste")
			(net "RST_BIC_I2C6_MUX_R_N")
		)
		(pad "2" smd circle
			(at -0.40005 0)
			(size 0 0)
			(layers "B.Cu" "B.Mask" "B.Paste")
			(net "RST_BIC_I2C6_MUX_N")
		)
	)
	(footprint ""
		(layer "B.Cu")
		(at 178.599846 -288.299906 90)
		(property "Reference" "C3111"
			(at 0 0 90)
			(layer "B.SilkS")
			(hide yes)
			(effects
				(font
					(size 1.27 1.27)
				)
				(justify mirror)
			)
		)
		(property "Value" ""
			(at 0 0 90)
			(layer "B.Fab")
			(effects
				(font
					(size 1.27 1.27)
				)
				(justify mirror)
			)
		)
		(duplicate_pad_numbers_are_jumpers no)
		(fp_line
			(start 0.299974 -0.150114)
			(end -0.299974 -0.150114)
			(stroke
				(width 0.1)
				(type default)
			)
			(layer "B.Fab")
		)
		(fp_line
			(start -0.299974 -0.150114)
			(end -0.299974 0.150114)
			(stroke
				(width 0.1)
				(type default)
			)
			(layer "B.Fab")
		)
		(fp_line
			(start 0.299974 0.150114)
			(end 0.299974 -0.150114)
			(stroke
				(width 0.1)
				(type default)
			)
			(layer "B.Fab")
		)
		(fp_line
			(start -0.299974 0.150114)
			(end 0.299974 0.150114)
			(stroke
				(width 0.1)
				(type default)
			)
			(layer "B.Fab")
		)
		(pad "1" smd rect
			(at 0.2667 0 270)
			(size 0.3048 0.381)
			(layers "B.Cu" "B.Mask" "B.Paste")
			(net "P1V25_PEX1")
		)
		(pad "2" smd rect
			(at -0.2667 0 270)
			(size 0.3048 0.381)
			(layers "B.Cu" "B.Mask" "B.Paste")
			(net "GND")
		)
	)
	(footprint ""
		(layer "B.Cu")
		(at 410.324808 -286.399732 90)
		(property "Reference" "C3481"
			(at 0 0 90)
			(layer "B.SilkS")
			(hide yes)
			(effects
				(font
					(size 1.27 1.27)
				)
				(justify mirror)
			)
		)
		(property "Value" ""
			(at 0 0 90)
			(layer "B.Fab")
			(effects
				(font
					(size 1.27 1.27)
				)
				(justify mirror)
			)
		)
		(duplicate_pad_numbers_are_jumpers no)
		(fp_line
			(start 0.299974 -0.150114)
			(end -0.299974 -0.150114)
			(stroke
				(width 0.1)
				(type default)
			)
			(layer "B.Fab")
		)
		(fp_line
			(start -0.299974 -0.150114)
			(end -0.299974 0.150114)
			(stroke
				(width 0.1)
				(type default)
			)
			(layer "B.Fab")
		)
		(fp_line
			(start 0.299974 0.150114)
			(end 0.299974 -0.150114)
			(stroke
				(width 0.1)
				(type default)
			)
			(layer "B.Fab")
		)
		(fp_line
			(start -0.299974 0.150114)
			(end 0.299974 0.150114)
			(stroke
				(width 0.1)
				(type default)
			)
			(layer "B.Fab")
		)
		(pad "1" smd rect
			(at 0.2667 0 270)
			(size 0.3048 0.381)
			(layers "B.Cu" "B.Mask" "B.Paste")
			(net "P1V25_SERDES_VDDPLL_PEX3")
		)
		(pad "2" smd rect
			(at -0.2667 0 270)
			(size 0.3048 0.381)
			(layers "B.Cu" "B.Mask" "B.Paste")
			(net "GND")
		)
	)
)
